#ISCELL
  logical_power cad_note *
  *
#ISCELL
  pure_quanta quanta_title_block_c *
  *
#ISCELL
  logical_power universal_gnd *
  page89_i1
#ISCELL
  standard offpage *
  page89_i10
#ISCELL
  standard tap *
  page89_i100
#ISCELL
  standard tap *
  page89_i101
#ISCELL
  standard tap *
  page89_i102
#ISCELL
  standard tap *
  page89_i103
#ISCELL
  standard tap *
  page89_i104
#ISCELL
  standard tap *
  page89_i105
#ISCELL
  standard tap *
  page89_i106
#ISCELL
  standard tap *
  page89_i107
#ISCELL
  standard tap *
  page89_i108
#ISCELL
  standard tap *
  page89_i109
#ISCELL
  logical_power vcc_core *
  page89_i11
#ISCELL
  standard tap *
  page89_i110
#ISCELL
  standard tap *
  page89_i111
#ISCELL
  standard offpage *
  page89_i112
#ISCELL
  standard tap *
  page89_i113
#ISCELL
  standard tap *
  page89_i114
#ISCELL
  standard tap *
  page89_i115
#ISCELL
  standard tap *
  page89_i116
#ISCELL
  standard tap *
  page89_i117
#ISCELL
  standard tap *
  page89_i118
#ISCELL
  logical_power universal_gnd *
  page89_i119
#ISCELL
  standard tap *
  page89_i12
#ISCELL
  logical_power universal_gnd *
  page89_i120
#CELL
  pure_quanta q_cap *
  page89_i121
#ISCELL
  logical_power vcc_core *
  page89_i122
#ISCELL
  standard offpage *
  page89_i123
#CELL
  pure_quanta q_cap *
  page89_i125
#ISCELL
  logical_power vcc_core *
  page89_i126
#CELL
  pure_quanta q_cap *
  page89_i127
#ISCELL
  logical_power universal_gnd *
  page89_i128
#ISCELL
  standard tap *
  page89_i129
#ISCELL
  standard offpage *
  page89_i13
#ISCELL
  standard tap *
  page89_i130
#ISCELL
  standard tap *
  page89_i131
#ISCELL
  standard tap *
  page89_i132
#ISCELL
  standard tap *
  page89_i133
#ISCELL
  standard tap *
  page89_i134
#ISCELL
  standard tap *
  page89_i135
#ISCELL
  standard tap *
  page89_i136
#ISCELL
  standard tap *
  page89_i137
#ISCELL
  standard tap *
  page89_i138
#ISCELL
  standard tap *
  page89_i139
#ISCELL
  standard offpage *
  page89_i14
#ISCELL
  standard tap *
  page89_i140
#ISCELL
  standard tap *
  page89_i141
#ISCELL
  standard tap *
  page89_i142
#ISCELL
  standard tap *
  page89_i143
#ISCELL
  standard tap *
  page89_i144
#ISCELL
  standard tap *
  page89_i145
#ISCELL
  standard tap *
  page89_i146
#ISCELL
  standard tap *
  page89_i147
#ISCELL
  standard tap *
  page89_i148
#ISCELL
  standard tap *
  page89_i149
#ISCELL
  standard offpage *
  page89_i15
#ISCELL
  standard tap *
  page89_i150
#ISCELL
  standard tap *
  page89_i151
#ISCELL
  standard tap *
  page89_i152
#ISCELL
  standard tap *
  page89_i153
#ISCELL
  standard tap *
  page89_i154
#ISCELL
  standard tap *
  page89_i155
#ISCELL
  standard tap *
  page89_i156
#ISCELL
  standard tap *
  page89_i157
#ISCELL
  standard tap *
  page89_i158
#ISCELL
  standard tap *
  page89_i159
#ISCELL
  standard offpage *
  page89_i16
#ISCELL
  standard tap *
  page89_i160
#ISCELL
  standard tap *
  page89_i161
#ISCELL
  standard tap *
  page89_i162
#ISCELL
  standard tap *
  page89_i163
#ISCELL
  standard tap *
  page89_i164
#ISCELL
  standard tap *
  page89_i165
#ISCELL
  standard offpage *
  page89_i166
#ISCELL
  standard offpage *
  page89_i167
#ISCELL
  standard offpage *
  page89_i168
#ISCELL
  standard tap *
  page89_i169
#ISCELL
  standard offpage *
  page89_i17
#ISCELL
  standard tap *
  page89_i170
#ISCELL
  standard tap *
  page89_i171
#ISCELL
  standard offpage *
  page89_i172
#ISCELL
  standard offpage *
  page89_i173
#ISCELL
  logical_power vcc_core *
  page89_i174
#CELL
  pure_quanta sconn288_adr50017p087cc *
  page89_i175
#ISCELL
  logical_power universal_gnd *
  page89_i176
#ISCELL
  standard offpage *
  page89_i177
#CELL
  pure_quanta sconn288_adr50017p087cc *
  page89_i178
#ISCELL
  standard offpage *
  page89_i179
#ISCELL
  standard offpage *
  page89_i18
#CELL
  pure_quanta q_res *
  page89_i180
#ISCELL
  standard offpage *
  page89_i19
#CELL
  pure_quanta q_res *
  page89_i2
#ISCELL
  standard offpage *
  page89_i20
#ISCELL
  standard offpage *
  page89_i21
#ISCELL
  standard offpage *
  page89_i22
#ISCELL
  standard offpage *
  page89_i23
#ISCELL
  standard tap *
  page89_i24
#ISCELL
  standard tap *
  page89_i25
#ISCELL
  standard tap *
  page89_i26
#ISCELL
  standard tap *
  page89_i27
#ISCELL
  standard tap *
  page89_i28
#ISCELL
  standard tap *
  page89_i29
#ISCELL
  standard offpage *
  page89_i3
#ISCELL
  standard tap *
  page89_i30
#ISCELL
  standard tap *
  page89_i31
#ISCELL
  standard tap *
  page89_i32
#ISCELL
  standard tap *
  page89_i33
#ISCELL
  standard tap *
  page89_i34
#ISCELL
  standard tap *
  page89_i35
#ISCELL
  standard tap *
  page89_i36
#ISCELL
  standard tap *
  page89_i37
#ISCELL
  standard tap *
  page89_i38
#ISCELL
  standard tap *
  page89_i39
#ISCELL
  standard offpage *
  page89_i4
#ISCELL
  standard tap *
  page89_i40
#ISCELL
  standard tap *
  page89_i41
#ISCELL
  standard tap *
  page89_i42
#ISCELL
  standard tap *
  page89_i43
#ISCELL
  standard tap *
  page89_i44
#ISCELL
  standard tap *
  page89_i45
#ISCELL
  standard tap *
  page89_i46
#ISCELL
  standard tap *
  page89_i47
#ISCELL
  standard tap *
  page89_i48
#ISCELL
  standard tap *
  page89_i49
#ISCELL
  standard offpage *
  page89_i5
#CELL
  pure_quanta sconn288_adr50017p087cc *
  page89_i50
#ISCELL
  standard tap *
  page89_i51
#ISCELL
  standard tap *
  page89_i52
#ISCELL
  standard tap *
  page89_i53
#ISCELL
  standard tap *
  page89_i54
#ISCELL
  standard tap *
  page89_i55
#ISCELL
  standard tap *
  page89_i56
#ISCELL
  standard tap *
  page89_i57
#ISCELL
  standard tap *
  page89_i58
#ISCELL
  standard tap *
  page89_i59
#ISCELL
  standard tap *
  page89_i60
#ISCELL
  standard tap *
  page89_i61
#ISCELL
  standard tap *
  page89_i62
#ISCELL
  standard tap *
  page89_i63
#ISCELL
  standard tap *
  page89_i64
#ISCELL
  standard tap *
  page89_i65
#ISCELL
  standard tap *
  page89_i66
#ISCELL
  standard tap *
  page89_i67
#ISCELL
  standard tap *
  page89_i68
#ISCELL
  standard tap *
  page89_i69
#ISCELL
  standard offpage *
  page89_i7
#ISCELL
  standard tap *
  page89_i70
#ISCELL
  standard tap *
  page89_i71
#ISCELL
  standard tap *
  page89_i72
#ISCELL
  standard tap *
  page89_i73
#ISCELL
  standard tap *
  page89_i74
#ISCELL
  standard tap *
  page89_i75
#ISCELL
  standard tap *
  page89_i76
#ISCELL
  standard tap *
  page89_i77
#ISCELL
  standard tap *
  page89_i78
#ISCELL
  standard tap *
  page89_i79
#ISCELL
  standard offpage *
  page89_i8
#ISCELL
  standard tap *
  page89_i80
#ISCELL
  standard tap *
  page89_i81
#ISCELL
  standard tap *
  page89_i82
#ISCELL
  standard tap *
  page89_i83
#ISCELL
  standard tap *
  page89_i84
#ISCELL
  standard tap *
  page89_i85
#ISCELL
  standard tap *
  page89_i86
#ISCELL
  standard tap *
  page89_i87
#ISCELL
  standard tap *
  page89_i88
#ISCELL
  standard tap *
  page89_i89
#ISCELL
  standard offpage *
  page89_i9
#ISCELL
  standard tap *
  page89_i90
#ISCELL
  standard tap *
  page89_i91
#ISCELL
  standard tap *
  page89_i92
#ISCELL
  standard tap *
  page89_i93
#ISCELL
  standard tap *
  page89_i94
#ISCELL
  standard tap *
  page89_i95
#ISCELL
  standard tap *
  page89_i96
#ISCELL
  standard tap *
  page89_i97
#ISCELL
  standard tap *
  page89_i98
#ISCELL
  standard tap *
  page89_i99
